# T6G (Grand Teton) — schematic netlist excerpt (pin names and nets, part order shuffled) for the footprints in the layout excerpt that follows; sources: Cadence DE-HDL packaged netlist, KiCad conversion of 04192023_DAF0TMB3IC0_F0TG_MB_C_brd_V02_OCP.brd

PC435_7  Q_CAP  0.1UF 25V 10% X7R  pkg 0402  page 222 : A = PVDDCR_CPU1_P1_VCCS ; B = GND
R41  Q_RES  0 5% CHIP  pkg 0402LF  page 131 : A = OCP_SFF_ISO_BIF2_EN ; B = OCP_SFF_BIF2_R_N

(kicad_pcb
	(version 20260206)
	(generator "pcbnew")
	(generator_version "10.0")
	(general
		(thickness 1.6)
		(legacy_teardrops no)
	)
	(paper "A4")
	(title_block
		(title "04192023_DAF0TMB3IC0_F0TG_MB_C_brd_V02_OCP.brd")
		(comment 1 "Grand Teton / footprints 3071-3072 of 8354")
	)
	(layers
		(0 "F.Cu" signal "TOP")
		(4 "In1.Cu" signal "GND")
		(6 "In2.Cu" signal "IN1")
		(8 "In3.Cu" signal "GND1")
		(10 "In4.Cu" signal "IN2")
		(12 "In5.Cu" signal "GND2")
		(14 "In6.Cu" signal "IN3")
		(16 "In7.Cu" signal "GND3")
		(18 "In8.Cu" signal "VCC")
		(20 "In9.Cu" signal "VCC1")
		(22 "In10.Cu" signal "GND4")
		(24 "In11.Cu" signal "IN4")
		(26 "In12.Cu" signal "GND5")
		(28 "In13.Cu" signal "IN5")
		(30 "In14.Cu" signal "GND6")
		(32 "In15.Cu" signal "IN6")
		(34 "In16.Cu" signal "GND7")
		(2 "B.Cu" signal "BOTTOM")
		(9 "F.Adhes" user "F.Adhesive")
		(11 "B.Adhes" user "B.Adhesive")
		(13 "F.Paste" user "Package Geometry/Pastemask Top")
		(15 "B.Paste" user "Package Geometry/Pastemask Bottom")
		(5 "F.SilkS" user "Ref Des/Silkscreen Top")
		(7 "B.SilkS" user "Ref Des/Silkscreen Bottom")
		(1 "F.Mask" user "Board Geometry/Soldermask Top")
		(3 "B.Mask" user "Board Geometry/Soldermask Bottom")
		(17 "Dwgs.User" user "User.Drawings")
		(19 "Cmts.User" user "User.Comments")
		(21 "Eco1.User" user "User.Eco1")
		(23 "Eco2.User" user "User.Eco2")
		(25 "Edge.Cuts" user "Board Geometry/Outline")
		(27 "Margin" user)
		(31 "F.CrtYd" user "Package Geometry/Place Bound Top")
		(29 "B.CrtYd" user "Package Geometry/Place Bound Bottom")
		(35 "F.Fab" user "Ref Des/Assembly Top")
		(33 "B.Fab" user "Ref Des/Assembly Bottom")
	)
	(footprint ""
		(layer "F.Cu")
		(at 436.005732 -16.199866 -90)
		(property "Reference" "R41"
			(at 0 0 270)
			(layer "F.SilkS")
			(hide yes)
			(effects
				(font
					(size 1.27 1.27)
				)
			)
		)
		(property "Value" ""
			(at 0 0 270)
			(layer "F.Fab")
			(effects
				(font
					(size 1.27 1.27)
				)
			)
		)
		(duplicate_pad_numbers_are_jumpers no)
		(fp_line
			(start -0.7874 0.4064)
			(end -0.7874 -0.4064)
			(stroke
				(width 0.1524)
				(type default)
			)
			(layer "F.SilkS")
		)
		(fp_line
			(start 0.7874 0.4064)
			(end -0.7874 0.4064)
			(stroke
				(width 0.1524)
				(type default)
			)
			(layer "F.SilkS")
		)
		(fp_line
			(start -0.7874 -0.4064)
			(end 0.7874 -0.4064)
			(stroke
				(width 0.1524)
				(type default)
			)
			(layer "F.SilkS")
		)
		(fp_line
			(start 0.7874 -0.4064)
			(end 0.7874 0.4064)
			(stroke
				(width 0.1524)
				(type default)
			)
			(layer "F.SilkS")
		)
		(fp_line
			(start -0.67945 0.3048)
			(end -0.67945 -0.305054)
			(stroke
				(width 0.1)
				(type default)
			)
			(layer "F.Fab")
		)
		(fp_line
			(start -0.12065 0.3048)
			(end -0.67945 0.3048)
			(stroke
				(width 0.1)
				(type default)
			)
			(layer "F.Fab")
		)
		(fp_line
			(start 0.120396 0.3048)
			(end 0.120396 0.2794)
			(stroke
				(width 0.1)
				(type default)
			)
			(layer "F.Fab")
		)
		(fp_line
			(start 0.67945 0.3048)
			(end 0.120396 0.3048)
			(stroke
				(width 0.1)
				(type default)
			)
			(layer "F.Fab")
		)
		(fp_line
			(start -0.12065 0.2794)
			(end -0.12065 0.3048)
			(stroke
				(width 0.1)
				(type default)
			)
			(layer "F.Fab")
		)
		(fp_line
			(start 0.120396 0.2794)
			(end -0.12065 0.2794)
			(stroke
				(width 0.1)
				(type default)
			)
			(layer "F.Fab")
		)
		(fp_line
			(start -0.12065 -0.2794)
			(end 0.12065 -0.2794)
			(stroke
				(width 0.1)
				(type default)
			)
			(layer "F.Fab")
		)
		(fp_line
			(start 0.12065 -0.2794)
			(end 0.12065 -0.3048)
			(stroke
				(width 0.1)
				(type default)
			)
			(layer "F.Fab")
		)
		(fp_line
			(start 0.12065 -0.3048)
			(end 0.67945 -0.3048)
			(stroke
				(width 0.1)
				(type default)
			)
			(layer "F.Fab")
		)
		(fp_line
			(start 0.67945 -0.3048)
			(end 0.67945 0.3048)
			(stroke
				(width 0.1)
				(type default)
			)
			(layer "F.Fab")
		)
		(fp_line
			(start -0.67945 -0.305054)
			(end -0.12065 -0.305054)
			(stroke
				(width 0.1)
				(type default)
			)
			(layer "F.Fab")
		)
		(fp_line
			(start -0.12065 -0.305054)
			(end -0.12065 -0.2794)
			(stroke
				(width 0.1)
				(type default)
			)
			(layer "F.Fab")
		)
		(pad "1" smd circle
			(at -0.40005 0 270)
			(size 0 0)
			(layers "F.Cu" "F.Mask" "F.Paste")
			(net "OCP_SFF_ISO_BIF2_EN")
		)
		(pad "2" smd circle
			(at 0.40005 0 270)
			(size 0 0)
			(layers "F.Cu" "F.Mask" "F.Paste")
			(net "OCP_SFF_BIF2_R_N")
		)
	)
	(footprint ""
		(layer "F.Cu")
		(at 50.84953 -351.578672 90)
		(property "Reference" "PC435_7"
			(at 0 0 90)
			(layer "F.SilkS")
			(hide yes)
			(effects
				(font
					(size 1.27 1.27)
				)
			)
		)
		(property "Value" ""
			(at 0 0 90)
			(layer "F.Fab")
			(effects
				(font
					(size 1.27 1.27)
				)
			)
		)
		(duplicate_pad_numbers_are_jumpers no)
		(fp_line
			(start 0.7874 -0.4064)
			(end 0.7874 0.4064)
			(stroke
				(width 0.1524)
				(type default)
			)
			(layer "F.SilkS")
		)
		(fp_line
			(start -0.7874 -0.4064)
			(end 0.7874 -0.4064)
			(stroke
				(width 0.1524)
				(type default)
			)
			(layer "F.SilkS")
		)
		(fp_line
			(start 0.7874 0.4064)
			(end -0.7874 0.4064)
			(stroke
				(width 0.1524)
				(type default)
			)
			(layer "F.SilkS")
		)
		(fp_line
			(start -0.7874 0.4064)
			(end -0.7874 -0.4064)
			(stroke
				(width 0.1524)
				(type default)
			)
			(layer "F.SilkS")
		)
		(fp_line
			(start -0.12065 -0.305054)
			(end -0.12065 -0.2794)
			(stroke
				(width 0.1)
				(type default)
			)
			(layer "F.Fab")
		)
		(fp_line
			(start -0.67945 -0.305054)
			(end -0.12065 -0.305054)
			(stroke
				(width 0.1)
				(type default)
			)
			(layer "F.Fab")
		)
		(fp_line
			(start 0.67945 -0.3048)
			(end 0.67945 0.3048)
			(stroke
				(width 0.1)
				(type default)
			)
			(layer "F.Fab")
		)
		(fp_line
			(start 0.12065 -0.3048)
			(end 0.67945 -0.3048)
			(stroke
				(width 0.1)
				(type default)
			)
			(layer "F.Fab")
		)
		(fp_line
			(start 0.12065 -0.2794)
			(end 0.12065 -0.3048)
			(stroke
				(width 0.1)
				(type default)
			)
			(layer "F.Fab")
		)
		(fp_line
			(start -0.12065 -0.2794)
			(end 0.12065 -0.2794)
			(stroke
				(width 0.1)
				(type default)
			)
			(layer "F.Fab")
		)
		(fp_line
			(start 0.120396 0.2794)
			(end -0.12065 0.2794)
			(stroke
				(width 0.1)
				(type default)
			)
			(layer "F.Fab")
		)
		(fp_line
			(start -0.12065 0.2794)
			(end -0.12065 0.3048)
			(stroke
				(width 0.1)
				(type default)
			)
			(layer "F.Fab")
		)
		(fp_line
			(start 0.67945 0.3048)
			(end 0.120396 0.3048)
			(stroke
				(width 0.1)
				(type default)
			)
			(layer "F.Fab")
		)
		(fp_line
			(start 0.120396 0.3048)
			(end 0.120396 0.2794)
			(stroke
				(width 0.1)
				(type default)
			)
			(layer "F.Fab")
		)
		(fp_line
			(start -0.12065 0.3048)
			(end -0.67945 0.3048)
			(stroke
				(width 0.1)
				(type default)
			)
			(layer "F.Fab")
		)
		(fp_line
			(start -0.67945 0.3048)
			(end -0.67945 -0.305054)
			(stroke
				(width 0.1)
				(type default)
			)
			(layer "F.Fab")
		)
		(pad "1" smd circle
			(at -0.40005 0 90)
			(size 0 0)
			(layers "F.Cu" "F.Mask" "F.Paste")
			(net "PVDDCR_CPU1_P1_VCCS")
		)
		(pad "2" smd circle
			(at 0.40005 0 90)
			(size 0 0)
			(layers "F.Cu" "F.Mask" "F.Paste")
			(net "GND")
		)
	)
)
